(kicad_pcb
	(version 20260206)
	(generator "pcbnew")
	(generator_version "10.0")
	(general
		(thickness 1.6)
		(legacy_teardrops no)
	)
	(paper "A4")
	(title_block
		(title "01162023_DA0F0TEBIF0_F0T_Expander_BD_F_brd_V02_OCP.brd")
		(comment 1 "Grand Teton / footprints 2117-2123 of 9728")
	)
	(layers
		(0 "F.Cu" signal "TOP")
		(4 "In1.Cu" signal "GND")
		(6 "In2.Cu" signal "VCC")
		(8 "In3.Cu" signal "VCC1")
		(10 "In4.Cu" signal "GND1")
		(12 "In5.Cu" signal "IN1")
		(14 "In6.Cu" signal "GND2")
		(16 "In7.Cu" signal "IN2")
		(18 "In8.Cu" signal "GND3")
		(20 "In9.Cu" signal "IN3")
		(22 "In10.Cu" signal "GND4")
		(24 "In11.Cu" signal "IN4")
		(26 "In12.Cu" signal "GND5")
		(28 "In13.Cu" signal "IN5")
		(30 "In14.Cu" signal "GND6")
		(32 "In15.Cu" signal "IN6")
		(34 "In16.Cu" signal "GND7")
		(2 "B.Cu" signal "BOTTOM")
		(9 "F.Adhes" user "F.Adhesive")
		(11 "B.Adhes" user "B.Adhesive")
		(13 "F.Paste" user "Package Geometry/Pastemask Top")
		(15 "B.Paste" user "Package Geometry/Pastemask Bottom")
		(5 "F.SilkS" user "Ref Des/Silkscreen Top")
		(7 "B.SilkS" user "Ref Des/Silkscreen Bottom")
		(1 "F.Mask" user "Board Geometry/Soldermask Top")
		(3 "B.Mask" user "Board Geometry/Soldermask Bottom")
		(17 "Dwgs.User" user "User.Drawings")
		(19 "Cmts.User" user "User.Comments")
		(21 "Eco1.User" user "User.Eco1")
		(23 "Eco2.User" user "User.Eco2")
		(25 "Edge.Cuts" user "Board Geometry/Outline")
		(27 "Margin" user)
		(31 "F.CrtYd" user "Package Geometry/Place Bound Top")
		(29 "B.CrtYd" user "Package Geometry/Place Bound Bottom")
		(35 "F.Fab" user "Ref Des/Assembly Top")
		(33 "B.Fab" user "Ref Des/Assembly Bottom")
	)
	(footprint ""
		(layer "F.Cu")
		(at 72.57542 -69.47916 180)
		(property "Reference" "PU78"
			(at -2.135124 -3.185922 90)
			(unlocked yes)
			(layer "F.SilkS")
			(effects
				(font
					(size 0.7874 0.5842)
					(thickness 0.1524)
				)
			)
		)
		(property "Value" ""
			(at 0 0 180)
			(layer "F.Fab")
			(effects
				(font
					(size 1.27 1.27)
				)
			)
		)
		(duplicate_pad_numbers_are_jumpers no)
		(fp_line
			(start 1.239774 1.495298)
			(end -1.239774 1.495298)
			(stroke
				(width 0.1524)
				(type default)
			)
			(layer "F.SilkS")
		)
		(fp_line
			(start 1.239774 -1.495298)
			(end 1.239774 1.495298)
			(stroke
				(width 0.1524)
				(type default)
			)
			(layer "F.SilkS")
		)
		(fp_line
			(start -1.239774 1.495298)
			(end -1.239774 -1.495298)
			(stroke
				(width 0.1524)
				(type default)
			)
			(layer "F.SilkS")
		)
		(fp_line
			(start -1.239774 -1.495298)
			(end 1.239774 -1.495298)
			(stroke
				(width 0.1524)
				(type default)
			)
			(layer "F.SilkS")
		)
		(fp_poly
			(pts
				(xy -1.830578 -1.378458) (xy -2.549144 -0.659892) (xy -1.471422 -0.300736)
			)
			(stroke
				(width 0)
				(type default)
			)
			(fill yes)
			(layer "F.SilkS")
		)
		(fp_line
			(start 0.8001 1.050036)
			(end -0.8001 1.050036)
			(stroke
				(width 0.1)
				(type default)
			)
			(layer "F.Fab")
		)
		(fp_line
			(start 0.8001 -1.050036)
			(end 0.8001 1.050036)
			(stroke
				(width 0.1)
				(type default)
			)
			(layer "F.Fab")
		)
		(fp_line
			(start -0.8001 1.050036)
			(end -0.8001 -1.050036)
			(stroke
				(width 0.1)
				(type default)
			)
			(layer "F.Fab")
		)
		(fp_line
			(start -0.8001 -1.050036)
			(end 0.8001 -1.050036)
			(stroke
				(width 0.1)
				(type default)
			)
			(layer "F.Fab")
		)
		(fp_poly
			(pts
				(xy -2.458974 -0.508) (xy -2.458974 0.508) (xy -1.442974 0)
			)
			(stroke
				(width 0)
				(type default)
			)
			(fill yes)
			(layer "F.Fab")
		)
		(pad "1_2" smd circle
			(at -0.374904 0 270)
			(size 0 0)
			(layers "F.Cu" "F.Mask" "F.Paste")
			(net "P12V_AUX")
		)
		(pad "3" smd rect
			(at -0.499872 0.999998 180)
			(size 0.254 0.7112)
			(layers "F.Cu" "F.Mask" "F.Paste")
			(net "GND")
		)
		(pad "4" smd rect
			(at 0 0.999998 180)
			(size 0.254 0.7112)
			(layers "F.Cu" "F.Mask" "F.Paste")
			(net "P12V_SSD2_CO_ILIMIT")
		)
		(pad "5" smd rect
			(at 0.499872 0.999998 180)
			(size 0.254 0.7112)
			(layers "F.Cu" "F.Mask" "F.Paste")
			(net "P12V_SSD2_CO_MODE")
		)
		(pad "6_7" smd circle
			(at 0.374904 0 90)
			(size 0 0)
			(layers "F.Cu" "F.Mask" "F.Paste")
			(net "P12V_SSD2_R")
		)
		(pad "8" smd rect
			(at 0.499872 -0.999998 180)
			(size 0.254 0.7112)
			(layers "F.Cu" "F.Mask" "F.Paste")
			(net "P12V_SSD2_CO_GATE")
		)
		(pad "9" smd rect
			(at 0 -0.999998 180)
			(size 0.254 0.7112)
			(layers "F.Cu" "F.Mask" "F.Paste")
			(net "P12V_SSD2_CO_EN")
		)
		(pad "10" smd rect
			(at -0.499872 -0.999998 180)
			(size 0.254 0.7112)
			(layers "F.Cu" "F.Mask" "F.Paste")
			(net "P12V_SSD2_CO_DV_DT")
		)
	)
	(footprint ""
		(layer "F.Cu")
		(at 3.686302 -251.312426 -90)
		(property "Reference" "C4241"
			(at 0 0 270)
			(layer "F.SilkS")
			(hide yes)
			(effects
				(font
					(size 1.27 1.27)
				)
			)
		)
		(property "Value" ""
			(at 0 0 270)
			(layer "F.Fab")
			(effects
				(font
					(size 1.27 1.27)
				)
			)
		)
		(duplicate_pad_numbers_are_jumpers no)
		(fp_line
			(start -1.2954 0.5842)
			(end -1.2954 -0.5842)
			(stroke
				(width 0.1524)
				(type default)
			)
			(layer "F.SilkS")
		)
		(fp_line
			(start 1.2954 0.5842)
			(end -1.2954 0.5842)
			(stroke
				(width 0.1524)
				(type default)
			)
			(layer "F.SilkS")
		)
		(fp_line
			(start -1.2954 -0.5842)
			(end 1.2954 -0.5842)
			(stroke
				(width 0.1524)
				(type default)
			)
			(layer "F.SilkS")
		)
		(fp_line
			(start 1.2954 -0.5842)
			(end 1.2954 0.5842)
			(stroke
				(width 0.1524)
				(type default)
			)
			(layer "F.SilkS")
		)
		(fp_line
			(start -0.8636 0.4572)
			(end -0.8636 0.4064)
			(stroke
				(width 0.1)
				(type default)
			)
			(layer "F.Fab")
		)
		(fp_line
			(start 0.8636 0.4572)
			(end -0.8636 0.4572)
			(stroke
				(width 0.1)
				(type default)
			)
			(layer "F.Fab")
		)
		(fp_line
			(start -1.1938 0.4064)
			(end -1.1938 -0.4064)
			(stroke
				(width 0.1)
				(type default)
			)
			(layer "F.Fab")
		)
		(fp_line
			(start -0.8636 0.4064)
			(end -1.1938 0.4064)
			(stroke
				(width 0.1)
				(type default)
			)
			(layer "F.Fab")
		)
		(fp_line
			(start 0.8636 0.4064)
			(end 0.8636 0.4572)
			(stroke
				(width 0.1)
				(type default)
			)
			(layer "F.Fab")
		)
		(fp_line
			(start 1.1938 0.4064)
			(end 0.8636 0.4064)
			(stroke
				(width 0.1)
				(type default)
			)
			(layer "F.Fab")
		)
		(fp_line
			(start -1.1938 -0.4064)
			(end -0.8636 -0.4064)
			(stroke
				(width 0.1)
				(type default)
			)
			(layer "F.Fab")
		)
		(fp_line
			(start -0.8636 -0.4064)
			(end -0.8636 -0.4572)
			(stroke
				(width 0.1)
				(type default)
			)
			(layer "F.Fab")
		)
		(fp_line
			(start 0.8636 -0.4064)
			(end 1.1938 -0.4064)
			(stroke
				(width 0.1)
				(type default)
			)
			(layer "F.Fab")
		)
		(fp_line
			(start 1.1938 -0.4064)
			(end 1.1938 0.4064)
			(stroke
				(width 0.1)
				(type default)
			)
			(layer "F.Fab")
		)
		(fp_line
			(start -0.8636 -0.4572)
			(end 0.8636 -0.4572)
			(stroke
				(width 0.1)
				(type default)
			)
			(layer "F.Fab")
		)
		(fp_line
			(start 0.8636 -0.4572)
			(end 0.8636 -0.4064)
			(stroke
				(width 0.1)
				(type default)
			)
			(layer "F.Fab")
		)
		(pad "1" smd rect
			(at -0.7366 0 180)
			(size 0.7112 0.8128)
			(layers "F.Cu" "F.Mask" "F.Paste")
			(net "P1V25_SERDES_VDDPLL_PEX0_C7")
		)
		(pad "2" smd rect
			(at 0.7366 0 180)
			(size 0.7112 0.8128)
			(layers "F.Cu" "F.Mask" "F.Paste")
			(net "GND")
		)
	)
	(footprint ""
		(layer "F.Cu")
		(at 126.221236 -177.039524)
		(property "Reference" "R1087"
			(at 0 0 0)
			(layer "F.SilkS")
			(hide yes)
			(effects
				(font
					(size 1.27 1.27)
				)
			)
		)
		(property "Value" ""
			(at 0 0 0)
			(layer "F.Fab")
			(effects
				(font
					(size 1.27 1.27)
				)
			)
		)
		(duplicate_pad_numbers_are_jumpers no)
		(fp_line
			(start -0.7874 -0.4064)
			(end 0.7874 -0.4064)
			(stroke
				(width 0.1524)
				(type default)
			)
			(layer "F.SilkS")
		)
		(fp_line
			(start -0.67945 -0.305054)
			(end -0.12065 -0.305054)
			(stroke
				(width 0.1)
				(type default)
			)
			(layer "F.Fab")
		)
		(fp_line
			(start -0.67945 0.3048)
			(end -0.67945 -0.305054)
			(stroke
				(width 0.1)
				(type default)
			)
			(layer "F.Fab")
		)
		(fp_line
			(start -0.12065 -0.305054)
			(end -0.12065 -0.2794)
			(stroke
				(width 0.1)
				(type default)
			)
			(layer "F.Fab")
		)
		(fp_line
			(start -0.12065 -0.2794)
			(end 0.12065 -0.2794)
			(stroke
				(width 0.1)
				(type default)
			)
			(layer "F.Fab")
		)
		(fp_line
			(start -0.12065 0.2794)
			(end -0.12065 0.3048)
			(stroke
				(width 0.1)
				(type default)
			)
			(layer "F.Fab")
		)
		(fp_line
			(start -0.12065 0.3048)
			(end -0.67945 0.3048)
			(stroke
				(width 0.1)
				(type default)
			)
			(layer "F.Fab")
		)
		(fp_line
			(start 0.120396 0.2794)
			(end -0.12065 0.2794)
			(stroke
				(width 0.1)
				(type default)
			)
			(layer "F.Fab")
		)
		(fp_line
			(start 0.120396 0.3048)
			(end 0.120396 0.2794)
			(stroke
				(width 0.1)
				(type default)
			)
			(layer "F.Fab")
		)
		(fp_line
			(start 0.12065 -0.3048)
			(end 0.67945 -0.3048)
			(stroke
				(width 0.1)
				(type default)
			)
			(layer "F.Fab")
		)
		(fp_line
			(start 0.12065 -0.2794)
			(end 0.12065 -0.3048)
			(stroke
				(width 0.1)
				(type default)
			)
			(layer "F.Fab")
		)
		(fp_line
			(start 0.67945 -0.3048)
			(end 0.67945 0.3048)
			(stroke
				(width 0.1)
				(type default)
			)
			(layer "F.Fab")
		)
		(fp_line
			(start 0.67945 0.3048)
			(end 0.120396 0.3048)
			(stroke
				(width 0.1)
				(type default)
			)
			(layer "F.Fab")
		)
		(pad "1" smd circle
			(at -0.40005 0)
			(size 0 0)
			(layers "F.Cu" "F.Mask" "F.Paste")
			(net "CLK_100M_DB2000QL_PEX0_S1_R_DP")
		)
		(pad "2" smd circle
			(at 0.40005 0)
			(size 0 0)
			(layers "F.Cu" "F.Mask" "F.Paste")
			(net "CLK_100M_DB2000QL_PEX0_S1_DP")
		)
	)
	(footprint ""
		(layer "F.Cu")
		(at 322.718684 -343.952322 90)
		(property "Reference" "C542"
			(at 0 0 90)
			(layer "F.SilkS")
			(hide yes)
			(effects
				(font
					(size 1.27 1.27)
				)
			)
		)
		(property "Value" ""
			(at 0 0 90)
			(layer "F.Fab")
			(effects
				(font
					(size 1.27 1.27)
				)
			)
		)
		(duplicate_pad_numbers_are_jumpers no)
		(fp_line
			(start 0.299974 -0.150114)
			(end 0.299974 0.150114)
			(stroke
				(width 0.1)
				(type default)
			)
			(layer "F.Fab")
		)
		(fp_line
			(start -0.299974 -0.150114)
			(end 0.299974 -0.150114)
			(stroke
				(width 0.1)
				(type default)
			)
			(layer "F.Fab")
		)
		(fp_line
			(start 0.299974 0.150114)
			(end -0.299974 0.150114)
			(stroke
				(width 0.1)
				(type default)
			)
			(layer "F.Fab")
		)
		(fp_line
			(start -0.299974 0.150114)
			(end -0.299974 -0.150114)
			(stroke
				(width 0.1)
				(type default)
			)
			(layer "F.Fab")
		)
		(pad "1" smd rect
			(at -0.2667 0 90)
			(size 0.3048 0.381)
			(layers "F.Cu" "F.Mask" "F.Paste")
			(net "P5E_PEX2_STN5_TX_DN<84>")
		)
		(pad "2" smd rect
			(at 0.2667 0 90)
			(size 0.3048 0.381)
			(layers "F.Cu" "F.Mask" "F.Paste")
			(net "P5E_PEX2_STN5_TX_C_DN<84>")
		)
	)
	(footprint ""
		(layer "F.Cu")
		(at 106.496358 -79.822294 90)
		(property "Reference" "R1137"
			(at 0 0 90)
			(layer "F.SilkS")
			(hide yes)
			(effects
				(font
					(size 1.27 1.27)
				)
			)
		)
		(property "Value" ""
			(at 0 0 90)
			(layer "F.Fab")
			(effects
				(font
					(size 1.27 1.27)
				)
			)
		)
		(duplicate_pad_numbers_are_jumpers no)
		(fp_line
			(start 0.7874 0.4064)
			(end -0.7874 0.4064)
			(stroke
				(width 0.1524)
				(type default)
			)
			(layer "F.SilkS")
		)
		(fp_line
			(start -0.12065 -0.305054)
			(end -0.12065 -0.2794)
			(stroke
				(width 0.1)
				(type default)
			)
			(layer "F.Fab")
		)
		(fp_line
			(start -0.67945 -0.305054)
			(end -0.12065 -0.305054)
			(stroke
				(width 0.1)
				(type default)
			)
			(layer "F.Fab")
		)
		(fp_line
			(start 0.67945 -0.3048)
			(end 0.67945 0.3048)
			(stroke
				(width 0.1)
				(type default)
			)
			(layer "F.Fab")
		)
		(fp_line
			(start 0.12065 -0.3048)
			(end 0.67945 -0.3048)
			(stroke
				(width 0.1)
				(type default)
			)
			(layer "F.Fab")
		)
		(fp_line
			(start 0.12065 -0.2794)
			(end 0.12065 -0.3048)
			(stroke
				(width 0.1)
				(type default)
			)
			(layer "F.Fab")
		)
		(fp_line
			(start -0.12065 -0.2794)
			(end 0.12065 -0.2794)
			(stroke
				(width 0.1)
				(type default)
			)
			(layer "F.Fab")
		)
		(fp_line
			(start 0.120396 0.2794)
			(end -0.12065 0.2794)
			(stroke
				(width 0.1)
				(type default)
			)
			(layer "F.Fab")
		)
		(fp_line
			(start -0.12065 0.2794)
			(end -0.12065 0.3048)
			(stroke
				(width 0.1)
				(type default)
			)
			(layer "F.Fab")
		)
		(fp_line
			(start 0.67945 0.3048)
			(end 0.120396 0.3048)
			(stroke
				(width 0.1)
				(type default)
			)
			(layer "F.Fab")
		)
		(fp_line
			(start 0.120396 0.3048)
			(end 0.120396 0.2794)
			(stroke
				(width 0.1)
				(type default)
			)
			(layer "F.Fab")
		)
		(fp_line
			(start -0.12065 0.3048)
			(end -0.67945 0.3048)
			(stroke
				(width 0.1)
				(type default)
			)
			(layer "F.Fab")
		)
		(fp_line
			(start -0.67945 0.3048)
			(end -0.67945 -0.305054)
			(stroke
				(width 0.1)
				(type default)
			)
			(layer "F.Fab")
		)
		(pad "1" smd circle
			(at -0.40005 0 90)
			(size 0 0)
			(layers "F.Cu" "F.Mask" "F.Paste")
			(net "CLK_100M_DB800ZL_SSD0_R_DN")
		)
		(pad "2" smd circle
			(at 0.40005 0 90)
			(size 0 0)
			(layers "F.Cu" "F.Mask" "F.Paste")
			(net "CLK_100M_DB800ZL_SSD0_DN")
		)
	)
	(footprint ""
		(layer "F.Cu")
		(at 435.24043 -141.404848 -90)
		(property "Reference" "R400"
			(at 0 0 270)
			(layer "F.SilkS")
			(hide yes)
			(effects
				(font
					(size 1.27 1.27)
				)
			)
		)
		(property "Value" ""
			(at 0 0 270)
			(layer "F.Fab")
			(effects
				(font
					(size 1.27 1.27)
				)
			)
		)
		(duplicate_pad_numbers_are_jumpers no)
		(fp_line
			(start -0.7874 0.4064)
			(end -0.7874 -0.4064)
			(stroke
				(width 0.1524)
				(type default)
			)
			(layer "F.SilkS")
		)
		(fp_line
			(start 0.7874 0.4064)
			(end -0.7874 0.4064)
			(stroke
				(width 0.1524)
				(type default)
			)
			(layer "F.SilkS")
		)
		(fp_line
			(start -0.7874 -0.4064)
			(end 0.7874 -0.4064)
			(stroke
				(width 0.1524)
				(type default)
			)
			(layer "F.SilkS")
		)
		(fp_line
			(start 0.7874 -0.4064)
			(end 0.7874 0.4064)
			(stroke
				(width 0.1524)
				(type default)
			)
			(layer "F.SilkS")
		)
		(fp_line
			(start -0.67945 0.3048)
			(end -0.67945 -0.305054)
			(stroke
				(width 0.1)
				(type default)
			)
			(layer "F.Fab")
		)
		(fp_line
			(start -0.12065 0.3048)
			(end -0.67945 0.3048)
			(stroke
				(width 0.1)
				(type default)
			)
			(layer "F.Fab")
		)
		(fp_line
			(start 0.120396 0.3048)
			(end 0.120396 0.2794)
			(stroke
				(width 0.1)
				(type default)
			)
			(layer "F.Fab")
		)
		(fp_line
			(start 0.67945 0.3048)
			(end 0.120396 0.3048)
			(stroke
				(width 0.1)
				(type default)
			)
			(layer "F.Fab")
		)
		(fp_line
			(start -0.12065 0.2794)
			(end -0.12065 0.3048)
			(stroke
				(width 0.1)
				(type default)
			)
			(layer "F.Fab")
		)
		(fp_line
			(start 0.120396 0.2794)
			(end -0.12065 0.2794)
			(stroke
				(width 0.1)
				(type default)
			)
			(layer "F.Fab")
		)
		(fp_line
			(start -0.12065 -0.2794)
			(end 0.12065 -0.2794)
			(stroke
				(width 0.1)
				(type default)
			)
			(layer "F.Fab")
		)
		(fp_line
			(start 0.12065 -0.2794)
			(end 0.12065 -0.3048)
			(stroke
				(width 0.1)
				(type default)
			)
			(layer "F.Fab")
		)
		(fp_line
			(start 0.12065 -0.3048)
			(end 0.67945 -0.3048)
			(stroke
				(width 0.1)
				(type default)
			)
			(layer "F.Fab")
		)
		(fp_line
			(start 0.67945 -0.3048)
			(end 0.67945 0.3048)
			(stroke
				(width 0.1)
				(type default)
			)
			(layer "F.Fab")
		)
		(fp_line
			(start -0.67945 -0.305054)
			(end -0.12065 -0.305054)
			(stroke
				(width 0.1)
				(type default)
			)
			(layer "F.Fab")
		)
		(fp_line
			(start -0.12065 -0.305054)
			(end -0.12065 -0.2794)
			(stroke
				(width 0.1)
				(type default)
			)
			(layer "F.Fab")
		)
		(pad "1" smd circle
			(at -0.40005 0 270)
			(size 0 0)
			(layers "F.Cu" "F.Mask" "F.Paste")
			(net "PRSNT_NIC7_R_N")
		)
		(pad "2" smd circle
			(at 0.40005 0 270)
			(size 0 0)
			(layers "F.Cu" "F.Mask" "F.Paste")
			(net "PRSNT_NIC7_N")
		)
	)
	(footprint ""
		(layer "F.Cu")
		(at 338.582 -201.168 -90)
		(property "Reference" "R4134"
			(at 0 0 270)
			(layer "F.SilkS")
			(hide yes)
			(effects
				(font
					(size 1.27 1.27)
				)
			)
		)
		(property "Value" ""
			(at 0 0 270)
			(layer "F.Fab")
			(effects
				(font
					(size 1.27 1.27)
				)
			)
		)
		(duplicate_pad_numbers_are_jumpers no)
		(fp_line
			(start -0.7874 0.4064)
			(end -0.7874 -0.4064)
			(stroke
				(width 0.1524)
				(type default)
			)
			(layer "F.SilkS")
		)
		(fp_line
			(start 0.7874 0.4064)
			(end -0.7874 0.4064)
			(stroke
				(width 0.1524)
				(type default)
			)
			(layer "F.SilkS")
		)
		(fp_line
			(start -0.7874 -0.4064)
			(end 0.7874 -0.4064)
			(stroke
				(width 0.1524)
				(type default)
			)
			(layer "F.SilkS")
		)
		(fp_line
			(start 0.7874 -0.4064)
			(end 0.7874 0.4064)
			(stroke
				(width 0.1524)
				(type default)
			)
			(layer "F.SilkS")
		)
		(fp_line
			(start -0.67945 0.3048)
			(end -0.67945 -0.305054)
			(stroke
				(width 0.1)
				(type default)
			)
			(layer "F.Fab")
		)
		(fp_line
			(start -0.12065 0.3048)
			(end -0.67945 0.3048)
			(stroke
				(width 0.1)
				(type default)
			)
			(layer "F.Fab")
		)
		(fp_line
			(start 0.120396 0.3048)
			(end 0.120396 0.2794)
			(stroke
				(width 0.1)
				(type default)
			)
			(layer "F.Fab")
		)
		(fp_line
			(start 0.67945 0.3048)
			(end 0.120396 0.3048)
			(stroke
				(width 0.1)
				(type default)
			)
			(layer "F.Fab")
		)
		(fp_line
			(start -0.12065 0.2794)
			(end -0.12065 0.3048)
			(stroke
				(width 0.1)
				(type default)
			)
			(layer "F.Fab")
		)
		(fp_line
			(start 0.120396 0.2794)
			(end -0.12065 0.2794)
			(stroke
				(width 0.1)
				(type default)
			)
			(layer "F.Fab")
		)
		(fp_line
			(start -0.12065 -0.2794)
			(end 0.12065 -0.2794)
			(stroke
				(width 0.1)
				(type default)
			)
			(layer "F.Fab")
		)
		(fp_line
			(start 0.12065 -0.2794)
			(end 0.12065 -0.3048)
			(stroke
				(width 0.1)
				(type default)
			)
			(layer "F.Fab")
		)
		(fp_line
			(start 0.12065 -0.3048)
			(end 0.67945 -0.3048)
			(stroke
				(width 0.1)
				(type default)
			)
			(layer "F.Fab")
		)
		(fp_line
			(start 0.67945 -0.3048)
			(end 0.67945 0.3048)
			(stroke
				(width 0.1)
				(type default)
			)
			(layer "F.Fab")
		)
		(fp_line
			(start -0.67945 -0.305054)
			(end -0.12065 -0.305054)
			(stroke
				(width 0.1)
				(type default)
			)
			(layer "F.Fab")
		)
		(fp_line
			(start -0.12065 -0.305054)
			(end -0.12065 -0.2794)
			(stroke
				(width 0.1)
				(type default)
			)
			(layer "F.Fab")
		)
		(pad "1" smd circle
			(at -0.40005 0 270)
			(size 0 0)
			(layers "F.Cu" "F.Mask" "F.Paste")
			(net "SSD12_CLK_EN_N")
		)
		(pad "2" smd circle
			(at 0.40005 0 270)
			(size 0 0)
			(layers "F.Cu" "F.Mask" "F.Paste")
			(net "SSD12_CLK_EN_R_N")
		)
	)
)
